# T6G (Grand Teton) — schematic netlist excerpt (pin names and nets, part order shuffled) for the footprints in the layout excerpt that follows; sources: Cadence DE-HDL packaged netlist, KiCad conversion of 04192023_DAF0TMB3IC0_F0TG_MB_C_brd_V02_OCP.brd

C359  Q_CAP  0.1UF 16V 10% X7R  pkg C0402  page 83 : A = P3V3_AUX ; B = GND

(kicad_pcb
	(version 20260206)
	(generator "pcbnew")
	(generator_version "10.0")
	(general
		(thickness 1.6)
		(legacy_teardrops no)
	)
	(paper "A4")
	(title_block
		(title "04192023_DAF0TMB3IC0_F0TG_MB_C_brd_V02_OCP.brd")
		(comment 1 "Grand Teton / footprints 5743-5743 of 8354")
	)
	(layers
		(0 "F.Cu" signal "TOP")
		(4 "In1.Cu" signal "GND")
		(6 "In2.Cu" signal "IN1")
		(8 "In3.Cu" signal "GND1")
		(10 "In4.Cu" signal "IN2")
		(12 "In5.Cu" signal "GND2")
		(14 "In6.Cu" signal "IN3")
		(16 "In7.Cu" signal "GND3")
		(18 "In8.Cu" signal "VCC")
		(20 "In9.Cu" signal "VCC1")
		(22 "In10.Cu" signal "GND4")
		(24 "In11.Cu" signal "IN4")
		(26 "In12.Cu" signal "GND5")
		(28 "In13.Cu" signal "IN5")
		(30 "In14.Cu" signal "GND6")
		(32 "In15.Cu" signal "IN6")
		(34 "In16.Cu" signal "GND7")
		(2 "B.Cu" signal "BOTTOM")
		(9 "F.Adhes" user "F.Adhesive")
		(11 "B.Adhes" user "B.Adhesive")
		(13 "F.Paste" user "Package Geometry/Pastemask Top")
		(15 "B.Paste" user "Package Geometry/Pastemask Bottom")
		(5 "F.SilkS" user "Ref Des/Silkscreen Top")
		(7 "B.SilkS" user "Ref Des/Silkscreen Bottom")
		(1 "F.Mask" user "Board Geometry/Soldermask Top")
		(3 "B.Mask" user "Board Geometry/Soldermask Bottom")
		(17 "Dwgs.User" user "User.Drawings")
		(19 "Cmts.User" user "User.Comments")
		(21 "Eco1.User" user "User.Eco1")
		(23 "Eco2.User" user "User.Eco2")
		(25 "Edge.Cuts" user "Board Geometry/Outline")
		(27 "Margin" user)
		(31 "F.CrtYd" user "Package Geometry/Place Bound Top")
		(29 "B.CrtYd" user "Package Geometry/Place Bound Bottom")
		(35 "F.Fab" user "Ref Des/Assembly Top")
		(33 "B.Fab" user "Ref Des/Assembly Bottom")
	)
	(footprint ""
		(layer "B.Cu")
		(at 184.332372 -113.462816 90)
		(property "Reference" "C359"
			(at 0 0 90)
			(layer "B.SilkS")
			(hide yes)
			(effects
				(font
					(size 1.27 1.27)
				)
				(justify mirror)
			)
		)
		(property "Value" ""
			(at 0 0 90)
			(layer "B.Fab")
			(effects
				(font
					(size 1.27 1.27)
				)
				(justify mirror)
			)
		)
		(duplicate_pad_numbers_are_jumpers no)
		(fp_line
			(start 0.69215 -0.2921)
			(end -0.69215 -0.2921)
			(stroke
				(width 0.1524)
				(type default)
			)
			(layer "B.SilkS")
		)
		(fp_line
			(start -0.69215 -0.2921)
			(end -0.69215 0.2921)
			(stroke
				(width 0.1524)
				(type default)
			)
			(layer "B.SilkS")
		)
		(fp_line
			(start 0.69215 0.2921)
			(end 0.69215 -0.2921)
			(stroke
				(width 0.1524)
				(type default)
			)
			(layer "B.SilkS")
		)
		(fp_line
			(start -0.69215 0.2921)
			(end 0.69215 0.2921)
			(stroke
				(width 0.1524)
				(type default)
			)
			(layer "B.SilkS")
		)
		(fp_line
			(start 0.51435 -0.2794)
			(end -0.51435 -0.2794)
			(stroke
				(width 0.1)
				(type default)
			)
			(layer "B.Fab")
		)
		(fp_line
			(start -0.51435 -0.2794)
			(end -0.51435 0.2794)
			(stroke
				(width 0.1)
				(type default)
			)
			(layer "B.Fab")
		)
		(fp_line
			(start 0.51435 0.2794)
			(end 0.51435 -0.2794)
			(stroke
				(width 0.1)
				(type default)
			)
			(layer "B.Fab")
		)
		(fp_line
			(start -0.51435 0.2794)
			(end 0.51435 0.2794)
			(stroke
				(width 0.1)
				(type default)
			)
			(layer "B.Fab")
		)
		(pad "1" smd circle
			(at 0.40005 0 270)
			(size 0 0)
			(layers "B.Cu" "B.Mask" "B.Paste")
			(net "P3V3_AUX")
		)
		(pad "2" smd circle
			(at -0.40005 0 270)
			(size 0 0)
			(layers "B.Cu" "B.Mask" "B.Paste")
			(net "GND")
		)
		(zone
			(layer "B.Cu")
			(hatch none 0.5)
			(connect_pads
				(clearance 0)
			)
			(min_thickness 0.25)
			(keepout
				(tracks not_allowed)
				(vias allowed)
				(pads allowed)
				(copperpour not_allowed)
				(footprints allowed)
			)
			(placement
				(enabled no)
				(sheetname "")
			)
			(fill
				(thermal_gap 0.5)
				(thermal_bridge_width 0.5)
				(island_removal_mode 0)
			)
			(polygon
				(pts
					(xy 184.186322 -113.362486) (xy 184.186322 -113.561876) (xy 184.244488 -113.653316) (xy 184.420002 -113.653316)
					(xy 184.478168 -113.561876) (xy 184.478168 -113.362486) (xy 184.420002 -113.272316) (xy 184.244742 -113.272316)
				)
			)
		)
	)
)
